# BASEBOARD_FAB2 (Tioga Pass) — schematic netlist excerpt (pin names and nets, part order shuffled) for the footprints in the layout excerpt that follows; sources: Cadence DE-HDL packaged netlist, KiCad conversion of Wiwynn_Tioga_Pass_MB.brd

EU7A2  IR354XX  IR35412 IC  pkg SM  page 236
  VOS  = P1V05_PCH_STBY
  LGND  = GND
  VCC  = VR_P1V05_PCH_STBY_PH1_VCIN
  VDRV  = P5V_STBY
  PGND(0)  = GND
  GL(0)  = TP_P1V05_PCH_GL_0
  PGND(1)  = GND
  SW  = VR_P1V05_PCH_STBY_PH1_PHASE_SW
  VIN(0)  = VR_FET_SW_P12V_STBY_PVDDQ_DEF
  VIN(1)  = VR_FET_SW_P12V_STBY_PVDDQ_DEF
  NC  = NC
  PHASE  = VR_P1V05_PCH_STBY_PH1_PHASE
  BOOST  = VR_P1V05_PCH_STBY_PH1_BOOT_R
  PWM  = VR_P1V05_PCH_STBY_PWM1
  EN  = P5V_STBY
  TOUT_FLT  = A_TSENSE_P1V05_PCH_STBY_TMON
  OCSET  = VR_P1V05_PCH_STBY_OCSET
  IOUT  = ISENSE_P1V05_PCH_STBY_PH1_IMON
  REFIN  = VR_P1V05_PCH_BIREF1
  PGND(2)  = GND
  GL(1)  = TP_P1V05_PCH_GL_1

(kicad_pcb
	(version 20260206)
	(generator "pcbnew")
	(generator_version "10.0")
	(general
		(thickness 1.6)
		(legacy_teardrops no)
	)
	(paper "A4")
	(title_block
		(title "Wiwynn_Tioga_Pass_MB.brd")
		(comment 1 "Tioga Pass / footprints 37-37 of 4770")
	)
	(layers
		(0 "F.Cu" signal "TOP")
		(4 "In1.Cu" signal "L2GND")
		(6 "In2.Cu" signal "L3")
		(8 "In3.Cu" signal "L4GND")
		(10 "In4.Cu" signal "L5")
		(12 "In5.Cu" signal "L6GND")
		(14 "In6.Cu" signal "L7VCC")
		(16 "In7.Cu" signal "L8VCC")
		(18 "In8.Cu" signal "L9GND")
		(20 "In9.Cu" signal "L10")
		(22 "In10.Cu" signal "L11GND")
		(24 "In11.Cu" signal "L12")
		(26 "In12.Cu" signal "L13GND")
		(2 "B.Cu" signal "BOTTOM")
		(9 "F.Adhes" user "F.Adhesive")
		(11 "B.Adhes" user "B.Adhesive")
		(13 "F.Paste" user "Package Geometry/Pastemask Top")
		(15 "B.Paste" user "Package Geometry/Pastemask Bottom")
		(5 "F.SilkS" user "Ref Des/Silkscreen Top")
		(7 "B.SilkS" user "Ref Des/Silkscreen Bottom")
		(1 "F.Mask" user "Board Geometry/Soldermask Top")
		(3 "B.Mask" user "Board Geometry/Soldermask Bottom")
		(17 "Dwgs.User" user "User.Drawings")
		(19 "Cmts.User" user "User.Comments")
		(21 "Eco1.User" user "User.Eco1")
		(23 "Eco2.User" user "User.Eco2")
		(25 "Edge.Cuts" user "Board Geometry/Outline")
		(27 "Margin" user)
		(31 "F.CrtYd" user "Package Geometry/Place Bound Top")
		(29 "B.CrtYd" user "Package Geometry/Place Bound Bottom")
		(35 "F.Fab" user "Ref Des/Assembly Top")
		(33 "B.Fab" user "Ref Des/Assembly Bottom")
	)
	(footprint ""
		(layer "F.Cu")
		(at 385.3942 -153.67)
		(property "Reference" "EU7A2"
			(at 3.98907 0.4318 90)
			(unlocked yes)
			(layer "F.SilkS")
			(effects
				(font
					(size 0.7874 0.5842)
					(thickness 0.1524)
				)
			)
		)
		(property "Value" ""
			(at 0 0 0)
			(layer "F.Fab")
			(effects
				(font
					(size 1.27 1.27)
				)
			)
		)
		(duplicate_pad_numbers_are_jumpers no)
		(fp_line
			(start -3.0099 -3.5052)
			(end 2.9718 -3.5052)
			(stroke
				(width 0.1524)
				(type default)
			)
			(layer "F.SilkS")
		)
		(fp_line
			(start -3.0099 3.429)
			(end -3.0099 -3.5052)
			(stroke
				(width 0.1524)
				(type default)
			)
			(layer "F.SilkS")
		)
		(fp_line
			(start 2.9718 -3.5052)
			(end 2.9718 3.429)
			(stroke
				(width 0.1524)
				(type default)
			)
			(layer "F.SilkS")
		)
		(fp_line
			(start 2.9718 3.429)
			(end -3.0099 3.429)
			(stroke
				(width 0.1524)
				(type default)
			)
			(layer "F.SilkS")
		)
		(fp_circle
			(center -3.057398 -2.678684)
			(end -2.930398 -2.678684)
			(stroke
				(width 0.254)
				(type default)
			)
			(fill no)
			(layer "F.SilkS")
		)
		(fp_poly
			(pts
				(xy -2.9972 -3.4925) (xy -2.9972 -2.6924) (xy -2.1971 -3.4925)
			)
			(stroke
				(width 0)
				(type default)
			)
			(fill yes)
			(layer "F.SilkS")
		)
		(fp_poly
			(pts
				(xy -2.549906 -3.050032) (xy -2.549906 3.050032) (xy 2.549906 3.050032) (xy 2.549906 -3.050032)
			)
			(stroke
				(width 0)
				(type default)
			)
			(fill no)
			(layer "F.CrtYd")
		)
		(fp_line
			(start -2.549906 -3.050032)
			(end 2.549906 -3.050032)
			(stroke
				(width 0.1)
				(type default)
			)
			(layer "F.Fab")
		)
		(fp_line
			(start -2.549906 3.050032)
			(end -2.549906 -3.050032)
			(stroke
				(width 0.1)
				(type default)
			)
			(layer "F.Fab")
		)
		(fp_line
			(start 2.549906 -3.050032)
			(end 2.549906 3.050032)
			(stroke
				(width 0.1)
				(type default)
			)
			(layer "F.Fab")
		)
		(fp_line
			(start 2.549906 3.050032)
			(end -2.549906 3.050032)
			(stroke
				(width 0.1)
				(type default)
			)
			(layer "F.Fab")
		)
		(fp_circle
			(center -3.057398 -2.678684)
			(end -2.930398 -2.678684)
			(stroke
				(width 0.254)
				(type default)
			)
			(fill no)
			(layer "F.Fab")
		)
		(pad "1" smd rect
			(at -2.39522 -2.279904)
			(size 0.7112 0.254)
			(layers "F.Cu" "F.Mask" "F.Paste")
			(net "P1V05_PCH_STBY")
		)
		(pad "2" smd rect
			(at -2.39522 -1.83007)
			(size 0.7112 0.254)
			(layers "F.Cu" "F.Mask" "F.Paste")
			(net "GND")
		)
		(pad "3" smd rect
			(at -2.39522 -1.379982)
			(size 0.7112 0.254)
			(layers "F.Cu" "F.Mask" "F.Paste")
			(net "VR_P1V05_PCH_STBY_PH1_VCIN")
		)
		(pad "4" smd rect
			(at -2.39522 -0.929894)
			(size 0.7112 0.254)
			(layers "F.Cu" "F.Mask" "F.Paste")
			(net "P5V_STBY")
		)
		(pad "5" smd rect
			(at -2.39522 -0.48006)
			(size 0.7112 0.254)
			(layers "F.Cu" "F.Mask" "F.Paste")
			(net "GND")
		)
		(pad "6" smd rect
			(at -2.39522 -0.029972)
			(size 0.7112 0.254)
			(layers "F.Cu" "F.Mask" "F.Paste")
			(net "TP_P1V05_PCH_GL_0")
		)
		(pad "7" smd custom
			(at 0.016764 1.145032)
			(size 0.53975 0.53975)
			(layers "F.Cu" "F.Mask" "F.Paste")
			(net "GND")
			(options
				(clearance outline)
				(anchor circle)
			)
			(primitives
				(gr_poly
					(pts
						(xy -2.7051 1.0795) (xy -2.7051 -0.3683) (xy -0.9271 -0.3683) (xy -0.9271 -1.0795) (xy 2.7051 -1.0795)
						(xy 2.7051 1.0795)
					)
					(width 0)
					(fill yes)
				)
			)
		)
		(pad "10" smd rect
			(at -0.008382 2.874772)
			(size 4.3434 0.6096)
			(layers "F.Cu" "F.Mask" "F.Paste")
			(net "VR_P1V05_PCH_STBY_PH1_PHASE_SW")
		)
		(pad "25" smd rect
			(at 1.548384 -1.283208)
			(size 2.3368 2.0066)
			(layers "F.Cu" "F.Mask" "F.Paste")
			(net "VR_FET_SW_P12V_STBY_PVDDQ_DEF")
		)
		(pad "30" smd rect
			(at 2.050034 -2.895092)
			(size 0.254 0.7112)
			(layers "F.Cu" "F.Mask" "F.Paste")
			(net "VR_FET_SW_P12V_STBY_PVDDQ_DEF")
		)
		(pad "31" smd rect
			(at 1.599946 -2.895092)
			(size 0.254 0.7112)
			(layers "F.Cu" "F.Mask" "F.Paste")
			(net "Net_360")
		)
		(pad "32" smd rect
			(at 1.150112 -2.895092)
			(size 0.254 0.7112)
			(layers "F.Cu" "F.Mask" "F.Paste")
			(net "VR_P1V05_PCH_STBY_PH1_PHASE")
		)
		(pad "33" smd rect
			(at 0.700024 -2.895092)
			(size 0.254 0.7112)
			(layers "F.Cu" "F.Mask" "F.Paste")
			(net "VR_P1V05_PCH_STBY_PH1_BOOT_R")
		)
		(pad "34" smd rect
			(at 0.249936 -2.895092)
			(size 0.254 0.7112)
			(layers "F.Cu" "F.Mask" "F.Paste")
			(net "VR_P1V05_PCH_STBY_PWM1")
		)
		(pad "35" smd rect
			(at -0.199898 -2.895092)
			(size 0.254 0.7112)
			(layers "F.Cu" "F.Mask" "F.Paste")
			(net "P5V_STBY")
		)
		(pad "36" smd rect
			(at -0.649986 -2.895092)
			(size 0.254 0.7112)
			(layers "F.Cu" "F.Mask" "F.Paste")
			(net "A_TSENSE_P1V05_PCH_STBY_TMON")
		)
		(pad "37" smd rect
			(at -1.100074 -2.895092)
			(size 0.254 0.7112)
			(layers "F.Cu" "F.Mask" "F.Paste")
			(net "VR_P1V05_PCH_STBY_OCSET")
		)
		(pad "38" smd rect
			(at -1.549908 -2.895092)
			(size 0.254 0.7112)
			(layers "F.Cu" "F.Mask" "F.Paste")
			(net "ISENSE_P1V05_PCH_STBY_PH1_IMON")
		)
		(pad "39" smd rect
			(at -1.999996 -2.895092)
			(size 0.254 0.7112)
			(layers "F.Cu" "F.Mask" "F.Paste")
			(net "VR_P1V05_PCH_BIREF1")
		)
		(pad "40" smd rect
			(at -0.871728 -1.283208)
			(size 1.8034 2.0066)
			(layers "F.Cu" "F.Mask" "F.Paste")
			(net "GND")
		)
		(pad "41" smd rect
			(at -1.533906 0.247904)
			(size 0.508 0.3556)
			(layers "F.Cu" "F.Mask" "F.Paste")
			(net "TP_P1V05_PCH_GL_1")
		)
	)
)
